# SCM (Grand Teton) — schematic netlist excerpt (pin names and nets, part order shuffled) for the footprints in the layout excerpt that follows; sources: Cadence DE-HDL packaged netlist, KiCad conversion of 12092022_DA0F0TMDCD0_F0T_Management_Board_D_brd_V3_OCP.brd

PL34  Q_INDUCTOR  4.7UH IND  pkg SMLF  page 51 : \1\ = SW_P5V_AUX_SW ; \2\ = P5V_AUX

J13  SCONN3_212H9103GBR1  SCONN3_212-H91-03GBR1 EMPTY  pkg HEADER1X3SXE_H367  page 31
  \1\  = PU_J13_P1
  \2\  = FM_DBG_SW_N
  \3\  = GND

R536  Q_RES  33.2 1% CHIP  pkg 0402LF  page 35 : A = BMC_CPLD_GPIO_12_R2 ; B = BMC_CPLD_GPIO_12

(kicad_pcb
	(version 20260206)
	(generator "pcbnew")
	(generator_version "10.0")
	(general
		(thickness 1.6)
		(legacy_teardrops no)
	)
	(paper "A4")
	(title_block
		(title "12092022_DA0F0TMDCD0_F0T_Management_Board_D_brd_V3_OCP.brd")
		(comment 1 "Grand Teton / footprints 107-109 of 1440")
	)
	(layers
		(0 "F.Cu" signal "TOP")
		(4 "In1.Cu" signal "GND")
		(6 "In2.Cu" signal "IN1")
		(8 "In3.Cu" signal "GND1")
		(10 "In4.Cu" signal "IN2")
		(12 "In5.Cu" signal "VCC")
		(14 "In6.Cu" signal "VCC1")
		(16 "In7.Cu" signal "IN3")
		(18 "In8.Cu" signal "GND2")
		(20 "In9.Cu" signal "IN4")
		(22 "In10.Cu" signal "GND3")
		(2 "B.Cu" signal "BOTTOM")
		(9 "F.Adhes" user "F.Adhesive")
		(11 "B.Adhes" user "B.Adhesive")
		(13 "F.Paste" user "Package Geometry/Pastemask Top")
		(15 "B.Paste" user "Package Geometry/Pastemask Bottom")
		(5 "F.SilkS" user "Ref Des/Silkscreen Top")
		(7 "B.SilkS" user "Ref Des/Silkscreen Bottom")
		(1 "F.Mask" user "Board Geometry/Soldermask Top")
		(3 "B.Mask" user "Board Geometry/Soldermask Bottom")
		(17 "Dwgs.User" user "User.Drawings")
		(19 "Cmts.User" user "User.Comments")
		(21 "Eco1.User" user "User.Eco1")
		(23 "Eco2.User" user "User.Eco2")
		(25 "Edge.Cuts" user "Board Geometry/Outline")
		(27 "Margin" user)
		(31 "F.CrtYd" user "Package Geometry/Place Bound Top")
		(29 "B.CrtYd" user "Package Geometry/Place Bound Bottom")
		(35 "F.Fab" user "Ref Des/Assembly Top")
		(33 "B.Fab" user "Ref Des/Assembly Bottom")
	)
	(footprint ""
		(layer "F.Cu")
		(at 8.955024 -39.94531 -90)
		(property "Reference" "PL34"
			(at 5.50037 6.228334 90)
			(unlocked yes)
			(layer "F.SilkS")
			(effects
				(font
					(size 0.7874 0.5842)
					(thickness 0.1524)
				)
				(justify left)
			)
		)
		(property "Value" ""
			(at 0 0 270)
			(layer "F.Fab")
			(effects
				(font
					(size 1.27 1.27)
				)
			)
		)
		(duplicate_pad_numbers_are_jumpers no)
		(fp_line
			(start -5.588 5.150104)
			(end 5.588 5.150104)
			(stroke
				(width 0.1524)
				(type default)
			)
			(layer "F.SilkS")
		)
		(fp_line
			(start 5.588 5.150104)
			(end 5.588 1.8034)
			(stroke
				(width 0.1524)
				(type default)
			)
			(layer "F.SilkS")
		)
		(fp_line
			(start -5.588 1.8288)
			(end -5.588 5.150104)
			(stroke
				(width 0.1524)
				(type default)
			)
			(layer "F.SilkS")
		)
		(fp_line
			(start 5.588 -1.8288)
			(end 5.588 -5.150104)
			(stroke
				(width 0.1524)
				(type default)
			)
			(layer "F.SilkS")
		)
		(fp_line
			(start -5.588 -5.150104)
			(end -5.588 -1.8542)
			(stroke
				(width 0.1524)
				(type default)
			)
			(layer "F.SilkS")
		)
		(fp_line
			(start 5.588 -5.150104)
			(end -5.588 -5.150104)
			(stroke
				(width 0.1524)
				(type default)
			)
			(layer "F.SilkS")
		)
		(fp_line
			(start -5.599938 5.150104)
			(end -5.599938 -5.150104)
			(stroke
				(width 0.1)
				(type default)
			)
			(layer "F.Fab")
		)
		(fp_line
			(start 5.599938 5.150104)
			(end -5.599938 5.150104)
			(stroke
				(width 0.1)
				(type default)
			)
			(layer "F.Fab")
		)
		(fp_line
			(start -5.599938 -5.150104)
			(end 5.599938 -5.150104)
			(stroke
				(width 0.1)
				(type default)
			)
			(layer "F.Fab")
		)
		(fp_line
			(start 5.599938 -5.150104)
			(end 5.599938 5.150104)
			(stroke
				(width 0.1)
				(type default)
			)
			(layer "F.Fab")
		)
		(pad "1" smd rect
			(at -4.338828 0 270)
			(size 3.302 3.302)
			(layers "F.Cu" "F.Mask" "F.Paste")
			(net "SW_P5V_AUX_SW")
		)
		(pad "2" smd rect
			(at 4.338828 0 270)
			(size 3.302 3.302)
			(layers "F.Cu" "F.Mask" "F.Paste")
			(net "P5V_AUX")
		)
	)
	(footprint ""
		(layer "F.Cu")
		(at 65.913 -17.653 180)
		(property "Reference" "J13"
			(at -1.651 -1.04267 0)
			(unlocked yes)
			(layer "F.SilkS")
			(effects
				(font
					(size 0.7874 0.5842)
					(thickness 0.1524)
				)
				(justify left)
			)
		)
		(property "Value" ""
			(at 0 0 180)
			(layer "F.Fab")
			(effects
				(font
					(size 1.27 1.27)
				)
			)
		)
		(duplicate_pad_numbers_are_jumpers no)
		(fp_line
			(start 1.249934 3.860038)
			(end 1.249934 0.6477)
			(stroke
				(width 0.1524)
				(type default)
			)
			(layer "F.SilkS")
		)
		(fp_line
			(start 1.249934 -0.6477)
			(end 1.249934 -3.860038)
			(stroke
				(width 0.1524)
				(type default)
			)
			(layer "F.SilkS")
		)
		(fp_line
			(start 1.249934 -3.860038)
			(end -1.249934 -3.860038)
			(stroke
				(width 0.1524)
				(type default)
			)
			(layer "F.SilkS")
		)
		(fp_line
			(start -1.249934 3.860038)
			(end 1.249934 3.860038)
			(stroke
				(width 0.1524)
				(type default)
			)
			(layer "F.SilkS")
		)
		(fp_line
			(start -1.249934 3.1877)
			(end -1.249934 3.860038)
			(stroke
				(width 0.1524)
				(type default)
			)
			(layer "F.SilkS")
		)
		(fp_line
			(start -1.249934 -1.8923)
			(end -1.249934 1.8923)
			(stroke
				(width 0.1524)
				(type default)
			)
			(layer "F.SilkS")
		)
		(fp_line
			(start -1.249934 -3.860038)
			(end -1.249934 -3.1877)
			(stroke
				(width 0.1524)
				(type default)
			)
			(layer "F.SilkS")
		)
		(fp_poly
			(pts
				(xy -4.2164 -3.048) (xy -3.2004 -2.54) (xy -4.2164 -2.032)
			)
			(stroke
				(width 0)
				(type default)
			)
			(fill yes)
			(layer "F.SilkS")
		)
		(fp_line
			(start 1.249934 3.860038)
			(end 1.249934 -3.860038)
			(stroke
				(width 0.1)
				(type default)
			)
			(layer "F.Fab")
		)
		(fp_line
			(start 1.249934 -3.860038)
			(end -1.249934 -3.860038)
			(stroke
				(width 0.1)
				(type default)
			)
			(layer "F.Fab")
		)
		(fp_line
			(start -1.249934 3.860038)
			(end 1.249934 3.860038)
			(stroke
				(width 0.1)
				(type default)
			)
			(layer "F.Fab")
		)
		(fp_line
			(start -1.249934 -3.860038)
			(end -1.249934 3.860038)
			(stroke
				(width 0.1)
				(type default)
			)
			(layer "F.Fab")
		)
		(fp_poly
			(pts
				(xy -4.2164 -3.048) (xy -3.2004 -2.54) (xy -4.2164 -2.032)
			)
			(stroke
				(width 0)
				(type default)
			)
			(fill yes)
			(layer "F.Fab")
		)
		(pad "1" smd rect
			(at -1.374902 -2.54 90)
			(size 1.016 2.7686)
			(layers "F.Cu" "F.Mask" "F.Paste")
			(net "PU_J13_P1")
		)
		(pad "2" smd rect
			(at 1.374902 0 90)
			(size 1.016 2.7686)
			(layers "F.Cu" "F.Mask" "F.Paste")
			(net "FM_DBG_SW_N")
		)
		(pad "3" smd rect
			(at -1.374902 2.54 90)
			(size 1.016 2.7686)
			(layers "F.Cu" "F.Mask" "F.Paste")
			(net "GND")
		)
	)
	(footprint ""
		(layer "F.Cu")
		(at 12.319 -94.488 180)
		(property "Reference" "R536"
			(at 0 0 180)
			(layer "F.SilkS")
			(hide yes)
			(effects
				(font
					(size 1.27 1.27)
				)
			)
		)
		(property "Value" ""
			(at 0 0 180)
			(layer "F.Fab")
			(effects
				(font
					(size 1.27 1.27)
				)
			)
		)
		(duplicate_pad_numbers_are_jumpers no)
		(fp_line
			(start 0.7874 0.4064)
			(end -0.7874 0.4064)
			(stroke
				(width 0.1524)
				(type default)
			)
			(layer "F.SilkS")
		)
		(fp_line
			(start 0.7874 -0.4064)
			(end 0.7874 0.4064)
			(stroke
				(width 0.1524)
				(type default)
			)
			(layer "F.SilkS")
		)
		(fp_line
			(start -0.7874 0.4064)
			(end -0.7874 -0.4064)
			(stroke
				(width 0.1524)
				(type default)
			)
			(layer "F.SilkS")
		)
		(fp_line
			(start -0.7874 -0.4064)
			(end 0.7874 -0.4064)
			(stroke
				(width 0.1524)
				(type default)
			)
			(layer "F.SilkS")
		)
		(fp_line
			(start 0.67945 0.3048)
			(end 0.120396 0.3048)
			(stroke
				(width 0.1)
				(type default)
			)
			(layer "F.Fab")
		)
		(fp_line
			(start 0.67945 -0.3048)
			(end 0.67945 0.3048)
			(stroke
				(width 0.1)
				(type default)
			)
			(layer "F.Fab")
		)
		(fp_line
			(start 0.12065 -0.2794)
			(end 0.12065 -0.3048)
			(stroke
				(width 0.1)
				(type default)
			)
			(layer "F.Fab")
		)
		(fp_line
			(start 0.12065 -0.3048)
			(end 0.67945 -0.3048)
			(stroke
				(width 0.1)
				(type default)
			)
			(layer "F.Fab")
		)
		(fp_line
			(start 0.120396 0.3048)
			(end 0.120396 0.2794)
			(stroke
				(width 0.1)
				(type default)
			)
			(layer "F.Fab")
		)
		(fp_line
			(start 0.120396 0.2794)
			(end -0.12065 0.2794)
			(stroke
				(width 0.1)
				(type default)
			)
			(layer "F.Fab")
		)
		(fp_line
			(start -0.12065 0.3048)
			(end -0.67945 0.3048)
			(stroke
				(width 0.1)
				(type default)
			)
			(layer "F.Fab")
		)
		(fp_line
			(start -0.12065 0.2794)
			(end -0.12065 0.3048)
			(stroke
				(width 0.1)
				(type default)
			)
			(layer "F.Fab")
		)
		(fp_line
			(start -0.12065 -0.2794)
			(end 0.12065 -0.2794)
			(stroke
				(width 0.1)
				(type default)
			)
			(layer "F.Fab")
		)
		(fp_line
			(start -0.12065 -0.305054)
			(end -0.12065 -0.2794)
			(stroke
				(width 0.1)
				(type default)
			)
			(layer "F.Fab")
		)
		(fp_line
			(start -0.67945 0.3048)
			(end -0.67945 -0.305054)
			(stroke
				(width 0.1)
				(type default)
			)
			(layer "F.Fab")
		)
		(fp_line
			(start -0.67945 -0.305054)
			(end -0.12065 -0.305054)
			(stroke
				(width 0.1)
				(type default)
			)
			(layer "F.Fab")
		)
		(pad "1" smd circle
			(at -0.40005 0 180)
			(size 0 0)
			(layers "F.Cu" "F.Mask" "F.Paste")
			(net "BMC_CPLD_GPIO_12_R2")
		)
		(pad "2" smd circle
			(at 0.40005 0 180)
			(size 0 0)
			(layers "F.Cu" "F.Mask" "F.Paste")
			(net "BMC_CPLD_GPIO_12")
		)
	)
)
